(kicad_pcb
	(version 20221018)
	(generator pcbnew)
	(general
    (thickness 1.518)
  )
	(paper "A4")
	(title_block
    (title "Kria K26 Devboard")
    (date "2024-03-26")
    (rev "1.2.5")
    (comment 1 "www.antmicro.com")
    (comment 2 "Antmicro Ltd.")
		(comment 9 "footprints 121-121 of 660")
	)
	(layers
    (0 "F.Cu" mixed)
    (1 "In1.Cu" power)
    (2 "In2.Cu" mixed)
    (3 "In3.Cu" power)
    (4 "In4.Cu" mixed)
    (5 "In5.Cu" power)
    (6 "In6.Cu" mixed)
    (31 "B.Cu" power)
    (32 "B.Adhes" user "B.Adhesive")
    (33 "F.Adhes" user "F.Adhesive")
    (34 "B.Paste" user)
    (35 "F.Paste" user)
    (36 "B.SilkS" user "B.Silkscreen")
    (37 "F.SilkS" user "F.Silkscreen")
    (38 "B.Mask" user)
    (39 "F.Mask" user)
    (40 "Dwgs.User" user "User.Drawings")
    (41 "Cmts.User" user "User.Comments")
    (42 "Eco1.User" user "User.Eco1")
    (43 "Eco2.User" user "User.Eco2")
    (44 "Edge.Cuts" user)
    (45 "Margin" user)
    (46 "B.CrtYd" user "B.Courtyard")
    (47 "F.CrtYd" user "F.Courtyard")
    (48 "B.Fab" user)
    (49 "F.Fab" user)
  )
	(footprint "kria-k26-devboard-footprints:QFN-68-1EP_8x8mm_P0.4mm" (layer "F.Cu")
    (at 148.26 118.3)
    (property "Author" "Antmicro")
    (property "License" "Apache-2.0")
    (property "MPN" "FT4232HPQ-TRAY")
    (property "Manufacturer" "FTDI Chip")
    (property "Sheetfile" "debug.kicad_sch")
    (property "Sheetname" "Debug and JTAG")
    (property "ki_description" "Interface Bridges, USB to UART, MPSSE, 1.62 V, 1.98 V, LQFP, 64 Pins, -40 °C")
    (property "ki_keywords" "SMT, INTERFACE, IC, CONTROLLER, USB, UART, I2C, SPI")
    (attr smd)
    (fp_text reference "U40" (at 5.17 -1.72 90) (layer "F.SilkS")
        (effects (font (size 0.7 0.7) (thickness 0.15)) (justify left bottom))
    )
    (fp_text value "FT4232HP_QFN" (at 0 5.2) (layer "F.Fab") hide
        (effects (font (size 0.7 0.7) (thickness 0.15)) (justify left bottom))
    )
    (fp_text user "${REFERENCE}" (at -4.425 7.2) (layer "F.Fab") hide
        (effects (font (size 0.7 0.7) (thickness 0.15)) (justify left bottom))
    )
    (fp_text user "Author: Antmicro" (at -4.425 8.4) (layer "F.Fab") hide
        (effects (font (size 0.7 0.7) (thickness 0.15)) (justify left bottom))
    )
    (fp_text user "License: Apache-2.0" (at -4.425 9.6) (layer "F.Fab") hide
        (effects (font (size 0.7 0.7) (thickness 0.15)) (justify left bottom))
    )
    (fp_line (start -4.1 4.1) (end -4.1 3.55)
      (stroke (width 0.15) (type solid)) (layer "F.SilkS"))
    (fp_line (start -4.0995 -3.501) (end -4.0995 -4.1)
      (stroke (width 0.15) (type solid)) (layer "F.SilkS"))
    (fp_line (start -3.55 4.1) (end -4.1 4.1)
      (stroke (width 0.15) (type solid)) (layer "F.SilkS"))
    (fp_line (start -3.5005 -4.1) (end -4.0995 -4.1)
      (stroke (width 0.15) (type solid)) (layer "F.SilkS"))
    (fp_line (start 3.5 -4.1) (end 4.1 -4.1)
      (stroke (width 0.15) (type solid)) (layer "F.SilkS"))
    (fp_line (start 3.55 4.1) (end 4.1 4.1)
      (stroke (width 0.15) (type solid)) (layer "F.SilkS"))
    (fp_line (start 4.1 -4.1) (end 4.1 -3.55)
      (stroke (width 0.15) (type solid)) (layer "F.SilkS"))
    (fp_line (start 4.1 4.1) (end 4.1 3.55)
      (stroke (width 0.15) (type solid)) (layer "F.SilkS"))
    (fp_circle (center -4.375 -3.5) (end -4.325 -3.5)
      (stroke (width 0.15) (type solid)) (fill solid) (layer "F.SilkS"))
    (fp_rect (start -4.25 -4.25) (end 4.25 4.25)
      (stroke (width 0.05) (type solid)) (fill none) (layer "F.CrtYd"))
    (fp_line (start -3.45 -4) (end -4 -3.45)
      (stroke (width 0.15) (type solid)) (layer "F.Fab"))
    (fp_rect (start -4 -4) (end 4 4)
      (stroke (width 0.15) (type solid)) (fill none) (layer "F.Fab"))
    (pad "" smd rect (at -1.7 -1.7) (size 1.5 1.5) (layers "F.Paste"))
    (pad "" smd rect (at -1.7 0) (size 1.5 1.5) (layers "F.Paste"))
    (pad "" smd rect (at -1.7 1.7) (size 1.5 1.5) (layers "F.Paste"))
    (pad "" smd rect (at 0 -1.7) (size 1.5 1.5) (layers "F.Paste"))
    (pad "" smd rect (at 0 0) (size 1.5 1.5) (layers "F.Paste"))
    (pad "" smd rect (at 0 1.7) (size 1.5 1.5) (layers "F.Paste"))
    (pad "" smd rect (at 1.7 -1.7) (size 1.5 1.5) (layers "F.Paste"))
    (pad "" smd rect (at 1.7 0) (size 1.5 1.5) (layers "F.Paste"))
    (pad "" smd rect (at 1.7 1.7) (size 1.5 1.5) (layers "F.Paste"))
    (pad "1" smd oval (at -3.95 -3.202 90) (size 0.25 0.6) (layers "F.Cu" "F.Paste" "F.Mask")
      (net 231 "/Debug and JTAG/EECLK") (pinfunction "EECLK") (pintype "output"))
    (pad "2" smd oval (at -3.95 -2.801 90) (size 0.25 0.6) (layers "F.Cu" "F.Paste" "F.Mask")
      (net 230 "/Debug and JTAG/EEDATA") (pinfunction "EEDATA") (pintype "bidirectional"))
    (pad "3" smd oval (at -3.95 -2.4 90) (size 0.25 0.6) (layers "F.Cu" "F.Paste" "F.Mask")
      (net 1 "GND") (pinfunction "TEST") (pintype "input"))
    (pad "4" smd oval (at -3.95 -2 90) (size 0.25 0.6) (layers "F.Cu" "F.Paste" "F.Mask")
      (net 681 "Net-(U40-~{RESET})") (pinfunction "~{RESET}") (pintype "input"))
    (pad "5" smd oval (at -3.95 -1.601 90) (size 0.25 0.6) (layers "F.Cu" "F.Paste" "F.Mask")
      (net 738 "unconnected-(U40-GPIO3-Pad5)") (pinfunction "GPIO3") (pintype "bidirectional+no_connect"))
    (pad "6" smd oval (at -3.95 -1.2 90) (size 0.25 0.6) (layers "F.Cu" "F.Paste" "F.Mask")
      (net 173 "/Debug and JTAG/FTDI_TCK") (pinfunction "ADBUS0") (pintype "bidirectional"))
    (pad "7" smd oval (at -3.95 -0.802 90) (size 0.25 0.6) (layers "F.Cu" "F.Paste" "F.Mask")
      (net 172 "/Debug and JTAG/FTDI_TDI") (pinfunction "ADBUS1") (pintype "bidirectional"))
    (pad "8" smd oval (at -3.95 -0.402 90) (size 0.25 0.6) (layers "F.Cu" "F.Paste" "F.Mask")
      (net 132 "/Debug and JTAG/USB_1V2") (pinfunction "V_{CORE}") (pintype "passive"))
    (pad "9" smd oval (at -3.95 0 90) (size 0.25 0.6) (layers "F.Cu" "F.Paste" "F.Mask")
      (net 1 "GND") (pinfunction "GND") (pintype "passive"))
    (pad "10" smd oval (at -3.95 0.4 90) (size 0.25 0.6) (layers "F.Cu" "F.Paste" "F.Mask")
      (net 138 "/Debug and JTAG/USB_3V3") (pinfunction "V_{CCIO}") (pintype "power_in"))
    (pad "11" smd oval (at -3.95 0.8 90) (size 0.25 0.6) (layers "F.Cu" "F.Paste" "F.Mask")
      (net 171 "/Debug and JTAG/FTDI_TDO") (pinfunction "ADBUS2") (pintype "bidirectional"))
    (pad "12" smd oval (at -3.95 1.199 90) (size 0.25 0.6) (layers "F.Cu" "F.Paste" "F.Mask")
      (net 170 "/Debug and JTAG/FTDI_TMS") (pinfunction "ADBUS3") (pintype "bidirectional"))
    (pad "13" smd oval (at -3.95 1.6 90) (size 0.25 0.6) (layers "F.Cu" "F.Paste" "F.Mask")
      (net 169 "/Debug and JTAG/JTAG_VCCO_ON") (pinfunction "ADBUS4") (pintype "bidirectional"))
    (pad "14" smd oval (at -3.95 1.999 90) (size 0.25 0.6) (layers "F.Cu" "F.Paste" "F.Mask")
      (net 159 "/Debug and JTAG/~{FTDI_LS_OE}") (pinfunction "ADBUS5") (pintype "bidirectional"))
    (pad "15" smd oval (at -3.95 2.398 90) (size 0.25 0.6) (layers "F.Cu" "F.Paste" "F.Mask")
      (net 168 "/Debug and JTAG/~{FTDI_PS_POR}") (pinfunction "ADBUS6") (pintype "bidirectional"))
    (pad "16" smd oval (at -3.95 2.798 90) (size 0.25 0.6) (layers "F.Cu" "F.Paste" "F.Mask")
      (net 167 "/Debug and JTAG/~{FTDI_PS_SRST}") (pinfunction "ADBUS7") (pintype "bidirectional"))
    (pad "17" smd oval (at -3.95 3.2 90) (size 0.25 0.6) (layers "F.Cu" "F.Paste" "F.Mask")
      (net 166 "/Debug and JTAG/FTDI_UARTB_TXD") (pinfunction "BDBUS0") (pintype "bidirectional"))
    (pad "18" smd oval (at -3.202 3.95) (size 0.25 0.6) (layers "F.Cu" "F.Paste" "F.Mask")
      (net 165 "/Debug and JTAG/FTDI_UARTB_RXD") (pinfunction "BDBUS1") (pintype "bidirectional"))
    (pad "19" smd oval (at -2.801 3.95) (size 0.25 0.6) (layers "F.Cu" "F.Paste" "F.Mask")
      (net 739 "unconnected-(U40-BDBUS2-Pad19)") (pinfunction "BDBUS2") (pintype "bidirectional+no_connect"))
    (pad "20" smd oval (at -2.4 3.95) (size 0.25 0.6) (layers "F.Cu" "F.Paste" "F.Mask")
      (net 740 "unconnected-(U40-BDBUS3-Pad20)") (pinfunction "BDBUS3") (pintype "bidirectional+no_connect"))
    (pad "21" smd oval (at -2 3.95) (size 0.25 0.6) (layers "F.Cu" "F.Paste" "F.Mask")
      (net 741 "unconnected-(U40-BDBUS4-Pad21)") (pinfunction "BDBUS4") (pintype "bidirectional+no_connect"))
    (pad "22" smd oval (at -1.601 3.95) (size 0.25 0.6) (layers "F.Cu" "F.Paste" "F.Mask")
      (net 742 "unconnected-(U40-BDBUS5-Pad22)") (pinfunction "BDBUS5") (pintype "bidirectional+no_connect"))
    (pad "23" smd oval (at -1.2 3.95) (size 0.25 0.6) (layers "F.Cu" "F.Paste" "F.Mask")
      (net 743 "unconnected-(U40-BDBUS6-Pad23)") (pinfunction "BDBUS6") (pintype "bidirectional+no_connect"))
    (pad "24" smd oval (at -0.802 3.95) (size 0.25 0.6) (layers "F.Cu" "F.Paste" "F.Mask")
      (net 744 "unconnected-(U40-BDBUS7-Pad24)") (pinfunction "BDBUS7") (pintype "bidirectional+no_connect"))
    (pad "25" smd oval (at -0.402 3.95) (size 0.25 0.6) (layers "F.Cu" "F.Paste" "F.Mask")
      (net 132 "/Debug and JTAG/USB_1V2") (pinfunction "V_{CORE}") (pintype "power_in"))
    (pad "26" smd oval (at 0 3.95) (size 0.25 0.6) (layers "F.Cu" "F.Paste" "F.Mask")
      (net 138 "/Debug and JTAG/USB_3V3") (pinfunction "V_{CCIO}") (pintype "passive"))
    (pad "27" smd oval (at 0.4 3.95) (size 0.25 0.6) (layers "F.Cu" "F.Paste" "F.Mask")
      (net 137 "/Debug and JTAG/XIN") (pinfunction "OSCI") (pintype "input"))
    (pad "28" smd oval (at 0.8 3.95) (size 0.25 0.6) (layers "F.Cu" "F.Paste" "F.Mask")
      (net 139 "/Debug and JTAG/XOUT") (pinfunction "OSCO") (pintype "output"))
    (pad "29" smd oval (at 1.199 3.95) (size 0.25 0.6) (layers "F.Cu" "F.Paste" "F.Mask")
      (net 1 "GND") (pinfunction "GND") (pintype "power_in"))
    (pad "30" smd oval (at 1.6 3.95) (size 0.25 0.6) (layers "F.Cu" "F.Paste" "F.Mask")
      (net 134 "/Debug and JTAG/VREGIN") (pinfunction "V_{REGIN}") (pintype "power_in"))
    (pad "31" smd oval (at 1.999 3.95) (size 0.25 0.6) (layers "F.Cu" "F.Paste" "F.Mask")
      (net 132 "/Debug and JTAG/USB_1V2") (pinfunction "V_{REGOUT}") (pintype "power_out"))
    (pad "32" smd oval (at 2.398 3.95) (size 0.25 0.6) (layers "F.Cu" "F.Paste" "F.Mask")
      (net 745 "unconnected-(U40-F_{SOURCE}-Pad32)") (pinfunction "F_{SOURCE}") (pintype "input+no_connect"))
    (pad "33" smd oval (at 2.798 3.95) (size 0.25 0.6) (layers "F.Cu" "F.Paste" "F.Mask")
      (net 746 "unconnected-(U40-V_{PP}-Pad33)") (pinfunction "V_{PP}") (pintype "power_in+no_connect"))
    (pad "34" smd oval (at 3.2 3.95) (size 0.25 0.6) (layers "F.Cu" "F.Paste" "F.Mask")
      (net 699 "Net-(U40-CDBUS0)") (pinfunction "CDBUS0") (pintype "bidirectional"))
    (pad "35" smd oval (at 3.95 3.2 90) (size 0.25 0.6) (layers "F.Cu" "F.Paste" "F.Mask")
      (net 700 "Net-(U40-CDBUS1)") (pinfunction "CDBUS1") (pintype "bidirectional"))
    (pad "36" smd oval (at 3.95 2.798 90) (size 0.25 0.6) (layers "F.Cu" "F.Paste" "F.Mask")
      (net 747 "unconnected-(U40-CDBUS2-Pad36)") (pinfunction "CDBUS2") (pintype "bidirectional+no_connect"))
    (pad "37" smd oval (at 3.95 2.398 90) (size 0.25 0.6) (layers "F.Cu" "F.Paste" "F.Mask")
      (net 748 "unconnected-(U40-CDBUS3-Pad37)") (pinfunction "CDBUS3") (pintype "bidirectional+no_connect"))
    (pad "38" smd oval (at 3.95 1.999 90) (size 0.25 0.6) (layers "F.Cu" "F.Paste" "F.Mask")
      (net 749 "unconnected-(U40-CDBUS4-Pad38)") (pinfunction "CDBUS4") (pintype "bidirectional+no_connect"))
    (pad "39" smd oval (at 3.95 1.6 90) (size 0.25 0.6) (layers "F.Cu" "F.Paste" "F.Mask")
      (net 138 "/Debug and JTAG/USB_3V3") (pinfunction "V_{CCIO}") (pintype "passive"))
    (pad "40" smd oval (at 3.95 1.199 90) (size 0.25 0.6) (layers "F.Cu" "F.Paste" "F.Mask")
      (net 750 "unconnected-(U40-CDBUS5-Pad40)") (pinfunction "CDBUS5") (pintype "bidirectional+no_connect"))
    (pad "41" smd oval (at 3.95 0.8 90) (size 0.25 0.6) (layers "F.Cu" "F.Paste" "F.Mask")
      (net 751 "unconnected-(U40-CDBUS6-Pad41)") (pinfunction "CDBUS6") (pintype "bidirectional+no_connect"))
    (pad "42" smd oval (at 3.95 0.4 90) (size 0.25 0.6) (layers "F.Cu" "F.Paste" "F.Mask")
      (net 752 "unconnected-(U40-CDBUS7-Pad42)") (pinfunction "CDBUS7") (pintype "bidirectional+no_connect"))
    (pad "43" smd oval (at 3.95 0 90) (size 0.25 0.6) (layers "F.Cu" "F.Paste" "F.Mask")
      (net 753 "unconnected-(U40-~{SUSPEND}-Pad43)") (pinfunction "~{SUSPEND}") (pintype "output+no_connect"))
    (pad "44" smd oval (at 3.95 -0.402 90) (size 0.25 0.6) (layers "F.Cu" "F.Paste" "F.Mask")
      (net 132 "/Debug and JTAG/USB_1V2") (pinfunction "V_{CORE}") (pintype "passive"))
    (pad "45" smd oval (at 3.95 -0.802 90) (size 0.25 0.6) (layers "F.Cu" "F.Paste" "F.Mask")
      (net 754 "unconnected-(U40-DDBUS0-Pad45)") (pinfunction "DDBUS0") (pintype "bidirectional+no_connect"))
    (pad "46" smd oval (at 3.95 -1.2 90) (size 0.25 0.6) (layers "F.Cu" "F.Paste" "F.Mask")
      (net 158 "/Debug and JTAG/FTDI_EEPROM_WC") (pinfunction "DDBUS1") (pintype "bidirectional"))
    (pad "47" smd oval (at 3.95 -1.601 90) (size 0.25 0.6) (layers "F.Cu" "F.Paste" "F.Mask")
      (net 755 "unconnected-(U40-DDBUS2-Pad47)") (pinfunction "DDBUS2") (pintype "bidirectional+no_connect"))
    (pad "48" smd oval (at 3.95 -2 90) (size 0.25 0.6) (layers "F.Cu" "F.Paste" "F.Mask")
      (net 758 "unconnected-(U40-DDBUS3-Pad48)") (pinfunction "DDBUS3") (pintype "bidirectional+no_connect"))
    (pad "49" smd oval (at 3.95 -2.4 90) (size 0.25 0.6) (layers "F.Cu" "F.Paste" "F.Mask")
      (net 759 "unconnected-(U40-DDBUS4-Pad49)") (pinfunction "DDBUS4") (pintype "bidirectional+no_connect"))
    (pad "50" smd oval (at 3.95 -2.801 90) (size 0.25 0.6) (layers "F.Cu" "F.Paste" "F.Mask")
      (net 760 "unconnected-(U40-DDBUS5-Pad50)") (pinfunction "DDBUS5") (pintype "bidirectional+no_connect"))
    (pad "51" smd oval (at 3.95 -3.202 90) (size 0.25 0.6) (layers "F.Cu" "F.Paste" "F.Mask")
      (net 138 "/Debug and JTAG/USB_3V3") (pinfunction "V_{CCIO}") (pintype "passive"))
    (pad "52" smd oval (at 3.2 -3.95) (size 0.25 0.6) (layers "F.Cu" "F.Paste" "F.Mask")
      (net 761 "unconnected-(U40-DDBUS6-Pad52)") (pinfunction "DDBUS6") (pintype "bidirectional+no_connect"))
    (pad "53" smd oval (at 2.798 -3.95) (size 0.25 0.6) (layers "F.Cu" "F.Paste" "F.Mask")
      (net 762 "unconnected-(U40-DDBUS7-Pad53)") (pinfunction "DDBUS7") (pintype "bidirectional+no_connect"))
    (pad "54" smd oval (at 2.398 -3.95) (size 0.25 0.6) (layers "F.Cu" "F.Paste" "F.Mask")
      (net 229 "/Debug and JTAG/PD_EN") (pinfunction "GPIO2") (pintype "bidirectional"))
    (pad "55" smd oval (at 1.999 -3.95) (size 0.25 0.6) (layers "F.Cu" "F.Paste" "F.Mask")
      (net 764 "unconnected-(U40-GPIO1-Pad55)") (pinfunction "GPIO1") (pintype "bidirectional+no_connect"))
    (pad "56" smd oval (at 1.6 -3.95) (size 0.25 0.6) (layers "F.Cu" "F.Paste" "F.Mask")
      (net 775 "unconnected-(U40-GPIO0-Pad56)") (pinfunction "GPIO0") (pintype "bidirectional+no_connect"))
    (pad "57" smd oval (at 1.199 -3.95) (size 0.25 0.6) (layers "F.Cu" "F.Paste" "F.Mask")
      (net 135 "/Debug and JTAG/VCC_USB") (pinfunction "V_{CC_USB}") (pintype "power_in"))
    (pad "58" smd oval (at 0.8 -3.95) (size 0.25 0.6) (layers "F.Cu" "F.Paste" "F.Mask")
      (net 234 "/Debug and JTAG/USB_N") (pinfunction "D-") (pintype "bidirectional"))
    (pad "59" smd oval (at 0.4 -3.95) (size 0.25 0.6) (layers "F.Cu" "F.Paste" "F.Mask")
      (net 233 "/Debug and JTAG/USB_P") (pinfunction "D+") (pintype "bidirectional"))
    (pad "60" smd oval (at 0 -3.95) (size 0.25 0.6) (layers "F.Cu" "F.Paste" "F.Mask")
      (net 680 "Net-(U40-REF)") (pinfunction "REF") (pintype "input"))
    (pad "61" smd oval (at -0.402 -3.95) (size 0.25 0.6) (layers "F.Cu" "F.Paste" "F.Mask")
      (net 133 "/Debug and JTAG/VCC_PD") (pinfunction "V_{CC_PD}") (pintype "power_in"))
    (pad "62" smd oval (at -0.802 -3.95) (size 0.25 0.6) (layers "F.Cu" "F.Paste" "F.Mask")
      (net 308 "/Debug and JTAG/USBC_CC2") (pinfunction "PD1_{CC2}") (pintype "bidirectional"))
    (pad "63" smd oval (at -1.2 -3.95) (size 0.25 0.6) (layers "F.Cu" "F.Paste" "F.Mask")
      (net 136 "/Debug and JTAG/PD1_SVBUS") (pinfunction "PD1_{SVBUS}") (pintype "input"))
    (pad "64" smd oval (at -1.601 -3.95) (size 0.25 0.6) (layers "F.Cu" "F.Paste" "F.Mask")
      (net 133 "/Debug and JTAG/VCC_PD") (pinfunction "PD1_{VCONN}") (pintype "power_in"))
    (pad "65" smd oval (at -2 -3.95) (size 0.25 0.6) (layers "F.Cu" "F.Paste" "F.Mask")
      (net 307 "/Debug and JTAG/USBC_CC1") (pinfunction "PD1_{CC1}") (pintype "bidirectional"))
    (pad "66" smd oval (at -2.4 -3.95) (size 0.25 0.6) (layers "F.Cu" "F.Paste" "F.Mask")
      (net 132 "/Debug and JTAG/USB_1V2") (pinfunction "V_{CORE}") (pintype "passive"))
    (pad "67" smd oval (at -2.801 -3.95) (size 0.25 0.6) (layers "F.Cu" "F.Paste" "F.Mask")
      (net 164 "/Debug and JTAG/~{FTDI_PWREN}") (pinfunction "~{PWREN}") (pintype "output"))
    (pad "68" smd oval (at -3.202 -3.95) (size 0.25 0.6) (layers "F.Cu" "F.Paste" "F.Mask")
      (net 232 "/Debug and JTAG/EECS") (pinfunction "EECS") (pintype "bidirectional"))
    (pad "EP" smd rect (at 0 0) (size 5.2 5.2) (layers "F.Cu" "F.Mask")
      (net 1 "GND") (pinfunction "EP") (pintype "passive"))
  )
)
